# S9S_MB_2U (Grand Teton) — schematic netlist excerpt (pin names and nets, part order shuffled) for the footprints in the layout excerpt that follows; sources: Cadence DE-HDL packaged netlist, KiCad conversion of 03242023_DA0F0TMBIJ0_F0T_Motherboard_J_brd_V01_OCP.brd

R1220  Q_RES  1K 1% EMPTY  pkg 0402LF  page 200 : A = P3V3_AUX ; B = FM_PCH_MCRO_LDO

U322  74LVC1G08W57  74LVC1G08W5-7 IC  pkg SOT25-5_0-95_3X1-6  page 158
  A  = HP_OCP_V3_1_RST_R
  B  = HP_LVC3_OCP_V3_1_P12V_PWRGD
  GND  = GND
  Y  = HP_LVC3_OCP_V3_1_PWRGD
  VCC  = P3V3_AUX

(kicad_pcb
	(version 20260206)
	(generator "pcbnew")
	(generator_version "10.0")
	(general
		(thickness 1.6)
		(legacy_teardrops no)
	)
	(paper "A4")
	(title_block
		(title "03242023_DA0F0TMBIJ0_F0T_Motherboard_J_brd_V01_OCP.brd")
		(comment 1 "Grand Teton / footprints 396-397 of 6105")
	)
	(layers
		(0 "F.Cu" signal "TOP")
		(4 "In1.Cu" signal "GND")
		(6 "In2.Cu" signal "IN1")
		(8 "In3.Cu" signal "GND1")
		(10 "In4.Cu" signal "IN2")
		(12 "In5.Cu" signal "GND2")
		(14 "In6.Cu" signal "IN3")
		(16 "In7.Cu" signal "GND3")
		(18 "In8.Cu" signal "VCC")
		(20 "In9.Cu" signal "VCC1")
		(22 "In10.Cu" signal "GND4")
		(24 "In11.Cu" signal "IN4")
		(26 "In12.Cu" signal "GND5")
		(28 "In13.Cu" signal "IN5")
		(30 "In14.Cu" signal "GND6")
		(32 "In15.Cu" signal "IN6")
		(34 "In16.Cu" signal "GND7")
		(2 "B.Cu" signal "BOTTOM")
		(9 "F.Adhes" user "F.Adhesive")
		(11 "B.Adhes" user "B.Adhesive")
		(13 "F.Paste" user "Package Geometry/Pastemask Top")
		(15 "B.Paste" user "Package Geometry/Pastemask Bottom")
		(5 "F.SilkS" user "Ref Des/Silkscreen Top")
		(7 "B.SilkS" user "Ref Des/Silkscreen Bottom")
		(1 "F.Mask" user "Board Geometry/Soldermask Top")
		(3 "B.Mask" user "Board Geometry/Soldermask Bottom")
		(17 "Dwgs.User" user "User.Drawings")
		(19 "Cmts.User" user "User.Comments")
		(21 "Eco1.User" user "User.Eco1")
		(23 "Eco2.User" user "User.Eco2")
		(25 "Edge.Cuts" user "Board Geometry/Outline")
		(27 "Margin" user)
		(31 "F.CrtYd" user "Package Geometry/Place Bound Top")
		(29 "B.CrtYd" user "Package Geometry/Place Bound Bottom")
		(35 "F.Fab" user "Ref Des/Assembly Top")
		(33 "B.Fab" user "Ref Des/Assembly Bottom")
	)
	(footprint ""
		(layer "F.Cu")
		(at 386.461 -31.968948 180)
		(property "Reference" "U322"
			(at 5.588 -0.15367 0)
			(unlocked yes)
			(layer "F.SilkS")
			(effects
				(font
					(size 0.7874 0.5842)
					(thickness 0.1524)
				)
				(justify left)
			)
		)
		(property "Value" ""
			(at 0 0 180)
			(layer "F.Fab")
			(effects
				(font
					(size 1.27 1.27)
				)
			)
		)
		(duplicate_pad_numbers_are_jumpers no)
		(fp_line
			(start 1.733296 1.549908)
			(end 1.733296 -1.549908)
			(stroke
				(width 0.1524)
				(type default)
			)
			(layer "F.SilkS")
		)
		(fp_line
			(start 1.733296 -1.549908)
			(end 0.660908 -1.549908)
			(stroke
				(width 0.1524)
				(type default)
			)
			(layer "F.SilkS")
		)
		(fp_line
			(start 0.660908 -1.549908)
			(end 0 -0.889)
			(stroke
				(width 0.1524)
				(type default)
			)
			(layer "F.SilkS")
		)
		(fp_line
			(start 0 -0.889)
			(end -0.660908 -1.549908)
			(stroke
				(width 0.1524)
				(type default)
			)
			(layer "F.SilkS")
		)
		(fp_line
			(start -0.660908 -1.549908)
			(end -1.733296 -1.549908)
			(stroke
				(width 0.1524)
				(type default)
			)
			(layer "F.SilkS")
		)
		(fp_line
			(start -1.733296 1.549908)
			(end 1.733296 1.549908)
			(stroke
				(width 0.1524)
				(type default)
			)
			(layer "F.SilkS")
		)
		(fp_line
			(start -1.733296 -1.549908)
			(end -1.733296 1.549908)
			(stroke
				(width 0.1524)
				(type default)
			)
			(layer "F.SilkS")
		)
		(fp_poly
			(pts
				(xy -2.4384 -1.20396) (xy -2.4384 -0.69596) (xy -1.9304 -0.94996)
			)
			(stroke
				(width 0)
				(type default)
			)
			(fill yes)
			(layer "F.SilkS")
		)
		(fp_line
			(start 0.849884 1.549908)
			(end 0.849884 -1.549908)
			(stroke
				(width 0.1)
				(type default)
			)
			(layer "F.Fab")
		)
		(fp_line
			(start 0.849884 -1.549908)
			(end -0.849884 -1.549908)
			(stroke
				(width 0.1)
				(type default)
			)
			(layer "F.Fab")
		)
		(fp_line
			(start -0.849884 1.549908)
			(end 0.849884 1.549908)
			(stroke
				(width 0.1)
				(type default)
			)
			(layer "F.Fab")
		)
		(fp_line
			(start -0.849884 -1.549908)
			(end -0.849884 1.549908)
			(stroke
				(width 0.1)
				(type default)
			)
			(layer "F.Fab")
		)
		(fp_poly
			(pts
				(xy -2.4384 -1.20396) (xy -2.4384 -0.69596) (xy -1.9304 -0.94996)
			)
			(stroke
				(width 0)
				(type default)
			)
			(fill yes)
			(layer "F.Fab")
		)
		(pad "1" smd rect
			(at -1.199896 -0.94996 90)
			(size 0.5588 0.8128)
			(layers "F.Cu" "F.Mask" "F.Paste")
			(net "HP_OCP_V3_1_RST_R")
		)
		(pad "2" smd rect
			(at -1.199896 0 90)
			(size 0.5588 0.8128)
			(layers "F.Cu" "F.Mask" "F.Paste")
			(net "HP_LVC3_OCP_V3_1_P12V_PWRGD")
		)
		(pad "3" smd rect
			(at -1.199896 0.94996 90)
			(size 0.5588 0.8128)
			(layers "F.Cu" "F.Mask" "F.Paste")
			(net "GND")
		)
		(pad "4" smd rect
			(at 1.199896 0.94996 90)
			(size 0.5588 0.8128)
			(layers "F.Cu" "F.Mask" "F.Paste")
			(net "HP_LVC3_OCP_V3_1_PWRGD")
		)
		(pad "5" smd rect
			(at 1.199896 -0.94996 90)
			(size 0.5588 0.8128)
			(layers "F.Cu" "F.Mask" "F.Paste")
			(net "P3V3_AUX")
		)
	)
	(footprint ""
		(layer "F.Cu")
		(at 320.190622 -59.299348)
		(property "Reference" "R1220"
			(at 0 0 0)
			(layer "F.SilkS")
			(hide yes)
			(effects
				(font
					(size 1.27 1.27)
				)
			)
		)
		(property "Value" ""
			(at 0 0 0)
			(layer "F.Fab")
			(effects
				(font
					(size 1.27 1.27)
				)
			)
		)
		(duplicate_pad_numbers_are_jumpers no)
		(fp_line
			(start -0.7874 -0.4064)
			(end 0.7874 -0.4064)
			(stroke
				(width 0.1524)
				(type default)
			)
			(layer "F.SilkS")
		)
		(fp_line
			(start -0.7874 0.4064)
			(end -0.7874 -0.4064)
			(stroke
				(width 0.1524)
				(type default)
			)
			(layer "F.SilkS")
		)
		(fp_line
			(start 0.7874 -0.4064)
			(end 0.7874 0.4064)
			(stroke
				(width 0.1524)
				(type default)
			)
			(layer "F.SilkS")
		)
		(fp_line
			(start 0.7874 0.4064)
			(end -0.7874 0.4064)
			(stroke
				(width 0.1524)
				(type default)
			)
			(layer "F.SilkS")
		)
		(fp_line
			(start -0.67945 -0.305054)
			(end -0.12065 -0.305054)
			(stroke
				(width 0.1)
				(type default)
			)
			(layer "F.Fab")
		)
		(fp_line
			(start -0.67945 0.3048)
			(end -0.67945 -0.305054)
			(stroke
				(width 0.1)
				(type default)
			)
			(layer "F.Fab")
		)
		(fp_line
			(start -0.12065 -0.305054)
			(end -0.12065 -0.2794)
			(stroke
				(width 0.1)
				(type default)
			)
			(layer "F.Fab")
		)
		(fp_line
			(start -0.12065 -0.2794)
			(end 0.12065 -0.2794)
			(stroke
				(width 0.1)
				(type default)
			)
			(layer "F.Fab")
		)
		(fp_line
			(start -0.12065 0.2794)
			(end -0.12065 0.3048)
			(stroke
				(width 0.1)
				(type default)
			)
			(layer "F.Fab")
		)
		(fp_line
			(start -0.12065 0.3048)
			(end -0.67945 0.3048)
			(stroke
				(width 0.1)
				(type default)
			)
			(layer "F.Fab")
		)
		(fp_line
			(start 0.120396 0.2794)
			(end -0.12065 0.2794)
			(stroke
				(width 0.1)
				(type default)
			)
			(layer "F.Fab")
		)
		(fp_line
			(start 0.120396 0.3048)
			(end 0.120396 0.2794)
			(stroke
				(width 0.1)
				(type default)
			)
			(layer "F.Fab")
		)
		(fp_line
			(start 0.12065 -0.3048)
			(end 0.67945 -0.3048)
			(stroke
				(width 0.1)
				(type default)
			)
			(layer "F.Fab")
		)
		(fp_line
			(start 0.12065 -0.2794)
			(end 0.12065 -0.3048)
			(stroke
				(width 0.1)
				(type default)
			)
			(layer "F.Fab")
		)
		(fp_line
			(start 0.67945 -0.3048)
			(end 0.67945 0.3048)
			(stroke
				(width 0.1)
				(type default)
			)
			(layer "F.Fab")
		)
		(fp_line
			(start 0.67945 0.3048)
			(end 0.120396 0.3048)
			(stroke
				(width 0.1)
				(type default)
			)
			(layer "F.Fab")
		)
		(pad "1" smd circle
			(at -0.40005 0)
			(size 0 0)
			(layers "F.Cu" "F.Mask" "F.Paste")
			(net "P3V3_AUX")
		)
		(pad "2" smd circle
			(at 0.40005 0)
			(size 0 0)
			(layers "F.Cu" "F.Mask" "F.Paste")
			(net "FM_PCH_MCRO_LDO")
		)
	)
)
